(kicad_pcb
	(version 20260206)
	(generator "pcbnew")
	(generator_version "10.0")
	(general
		(thickness 1.6)
		(legacy_teardrops no)
	)
	(paper "A4")
	(title_block
		(title "01162023_DA0F0TEBIF0_F0T_Expander_BD_F_brd_V02_OCP.brd")
		(comment 1 "Grand Teton / footprints 4458-4463 of 9728")
	)
	(layers
		(0 "F.Cu" signal "TOP")
		(4 "In1.Cu" signal "GND")
		(6 "In2.Cu" signal "VCC")
		(8 "In3.Cu" signal "VCC1")
		(10 "In4.Cu" signal "GND1")
		(12 "In5.Cu" signal "IN1")
		(14 "In6.Cu" signal "GND2")
		(16 "In7.Cu" signal "IN2")
		(18 "In8.Cu" signal "GND3")
		(20 "In9.Cu" signal "IN3")
		(22 "In10.Cu" signal "GND4")
		(24 "In11.Cu" signal "IN4")
		(26 "In12.Cu" signal "GND5")
		(28 "In13.Cu" signal "IN5")
		(30 "In14.Cu" signal "GND6")
		(32 "In15.Cu" signal "IN6")
		(34 "In16.Cu" signal "GND7")
		(2 "B.Cu" signal "BOTTOM")
		(9 "F.Adhes" user "F.Adhesive")
		(11 "B.Adhes" user "B.Adhesive")
		(13 "F.Paste" user "Package Geometry/Pastemask Top")
		(15 "B.Paste" user "Package Geometry/Pastemask Bottom")
		(5 "F.SilkS" user "Ref Des/Silkscreen Top")
		(7 "B.SilkS" user "Ref Des/Silkscreen Bottom")
		(1 "F.Mask" user "Board Geometry/Soldermask Top")
		(3 "B.Mask" user "Board Geometry/Soldermask Bottom")
		(17 "Dwgs.User" user "User.Drawings")
		(19 "Cmts.User" user "User.Comments")
		(21 "Eco1.User" user "User.Eco1")
		(23 "Eco2.User" user "User.Eco2")
		(25 "Edge.Cuts" user "Board Geometry/Outline")
		(27 "Margin" user)
		(31 "F.CrtYd" user "Package Geometry/Place Bound Top")
		(29 "B.CrtYd" user "Package Geometry/Place Bound Bottom")
		(35 "F.Fab" user "Ref Des/Assembly Top")
		(33 "B.Fab" user "Ref Des/Assembly Bottom")
	)
	(footprint ""
		(layer "F.Cu")
		(at 269.750286 -252.356874 -90)
		(property "Reference" "R1366"
			(at 0 0 270)
			(layer "F.SilkS")
			(hide yes)
			(effects
				(font
					(size 1.27 1.27)
				)
			)
		)
		(property "Value" ""
			(at 0 0 270)
			(layer "F.Fab")
			(effects
				(font
					(size 1.27 1.27)
				)
			)
		)
		(duplicate_pad_numbers_are_jumpers no)
		(fp_line
			(start -0.7874 0.4064)
			(end -0.7874 -0.4064)
			(stroke
				(width 0.1524)
				(type default)
			)
			(layer "F.SilkS")
		)
		(fp_line
			(start 0.7874 0.4064)
			(end -0.7874 0.4064)
			(stroke
				(width 0.1524)
				(type default)
			)
			(layer "F.SilkS")
		)
		(fp_line
			(start -0.7874 -0.4064)
			(end 0.7874 -0.4064)
			(stroke
				(width 0.1524)
				(type default)
			)
			(layer "F.SilkS")
		)
		(fp_line
			(start 0.7874 -0.4064)
			(end 0.7874 0.4064)
			(stroke
				(width 0.1524)
				(type default)
			)
			(layer "F.SilkS")
		)
		(fp_line
			(start -0.67945 0.3048)
			(end -0.67945 -0.305054)
			(stroke
				(width 0.1)
				(type default)
			)
			(layer "F.Fab")
		)
		(fp_line
			(start -0.12065 0.3048)
			(end -0.67945 0.3048)
			(stroke
				(width 0.1)
				(type default)
			)
			(layer "F.Fab")
		)
		(fp_line
			(start 0.120396 0.3048)
			(end 0.120396 0.2794)
			(stroke
				(width 0.1)
				(type default)
			)
			(layer "F.Fab")
		)
		(fp_line
			(start 0.67945 0.3048)
			(end 0.120396 0.3048)
			(stroke
				(width 0.1)
				(type default)
			)
			(layer "F.Fab")
		)
		(fp_line
			(start -0.12065 0.2794)
			(end -0.12065 0.3048)
			(stroke
				(width 0.1)
				(type default)
			)
			(layer "F.Fab")
		)
		(fp_line
			(start 0.120396 0.2794)
			(end -0.12065 0.2794)
			(stroke
				(width 0.1)
				(type default)
			)
			(layer "F.Fab")
		)
		(fp_line
			(start -0.12065 -0.2794)
			(end 0.12065 -0.2794)
			(stroke
				(width 0.1)
				(type default)
			)
			(layer "F.Fab")
		)
		(fp_line
			(start 0.12065 -0.2794)
			(end 0.12065 -0.3048)
			(stroke
				(width 0.1)
				(type default)
			)
			(layer "F.Fab")
		)
		(fp_line
			(start 0.12065 -0.3048)
			(end 0.67945 -0.3048)
			(stroke
				(width 0.1)
				(type default)
			)
			(layer "F.Fab")
		)
		(fp_line
			(start 0.67945 -0.3048)
			(end 0.67945 0.3048)
			(stroke
				(width 0.1)
				(type default)
			)
			(layer "F.Fab")
		)
		(fp_line
			(start -0.67945 -0.305054)
			(end -0.12065 -0.305054)
			(stroke
				(width 0.1)
				(type default)
			)
			(layer "F.Fab")
		)
		(fp_line
			(start -0.12065 -0.305054)
			(end -0.12065 -0.2794)
			(stroke
				(width 0.1)
				(type default)
			)
			(layer "F.Fab")
		)
		(pad "1" smd circle
			(at -0.40005 0 270)
			(size 0 0)
			(layers "F.Cu" "F.Mask" "F.Paste")
			(net "GND")
		)
		(pad "2" smd circle
			(at 0.40005 0 270)
			(size 0 0)
			(layers "F.Cu" "F.Mask" "F.Paste")
			(net "PEX2_MODE_SEL10")
		)
	)
	(footprint ""
		(layer "F.Cu")
		(at 82.661506 -145.311114 180)
		(property "Reference" "C13"
			(at 0 0 180)
			(layer "F.SilkS")
			(hide yes)
			(effects
				(font
					(size 1.27 1.27)
				)
			)
		)
		(property "Value" ""
			(at 0 0 180)
			(layer "F.Fab")
			(effects
				(font
					(size 1.27 1.27)
				)
			)
		)
		(duplicate_pad_numbers_are_jumpers no)
		(fp_line
			(start 0.299974 0.150114)
			(end -0.299974 0.150114)
			(stroke
				(width 0.1)
				(type default)
			)
			(layer "F.Fab")
		)
		(fp_line
			(start 0.299974 -0.150114)
			(end 0.299974 0.150114)
			(stroke
				(width 0.1)
				(type default)
			)
			(layer "F.Fab")
		)
		(fp_line
			(start -0.299974 0.150114)
			(end -0.299974 -0.150114)
			(stroke
				(width 0.1)
				(type default)
			)
			(layer "F.Fab")
		)
		(fp_line
			(start -0.299974 -0.150114)
			(end 0.299974 -0.150114)
			(stroke
				(width 0.1)
				(type default)
			)
			(layer "F.Fab")
		)
		(pad "1" smd rect
			(at -0.2667 0 180)
			(size 0.3048 0.381)
			(layers "F.Cu" "F.Mask" "F.Paste")
			(net "P5E_PEX0_STN0_TX_DP<9>")
		)
		(pad "2" smd rect
			(at 0.2667 0 180)
			(size 0.3048 0.381)
			(layers "F.Cu" "F.Mask" "F.Paste")
			(net "P5E_PEX0_STN0_TX_C_DP<9>")
		)
	)
	(footprint ""
		(layer "F.Cu")
		(at 394.555218 -35.876738)
		(property "Reference" "R6116"
			(at 0 0 0)
			(layer "F.SilkS")
			(hide yes)
			(effects
				(font
					(size 1.27 1.27)
				)
			)
		)
		(property "Value" ""
			(at 0 0 0)
			(layer "F.Fab")
			(effects
				(font
					(size 1.27 1.27)
				)
			)
		)
		(duplicate_pad_numbers_are_jumpers no)
		(fp_line
			(start -0.7874 -0.4064)
			(end 0.7874 -0.4064)
			(stroke
				(width 0.1524)
				(type default)
			)
			(layer "F.SilkS")
		)
		(fp_line
			(start -0.7874 0.4064)
			(end -0.7874 -0.4064)
			(stroke
				(width 0.1524)
				(type default)
			)
			(layer "F.SilkS")
		)
		(fp_line
			(start 0.7874 -0.4064)
			(end 0.7874 0.4064)
			(stroke
				(width 0.1524)
				(type default)
			)
			(layer "F.SilkS")
		)
		(fp_line
			(start 0.7874 0.4064)
			(end -0.7874 0.4064)
			(stroke
				(width 0.1524)
				(type default)
			)
			(layer "F.SilkS")
		)
		(fp_line
			(start -0.67945 -0.305054)
			(end -0.12065 -0.305054)
			(stroke
				(width 0.1)
				(type default)
			)
			(layer "F.Fab")
		)
		(fp_line
			(start -0.67945 0.3048)
			(end -0.67945 -0.305054)
			(stroke
				(width 0.1)
				(type default)
			)
			(layer "F.Fab")
		)
		(fp_line
			(start -0.12065 -0.305054)
			(end -0.12065 -0.2794)
			(stroke
				(width 0.1)
				(type default)
			)
			(layer "F.Fab")
		)
		(fp_line
			(start -0.12065 -0.2794)
			(end 0.12065 -0.2794)
			(stroke
				(width 0.1)
				(type default)
			)
			(layer "F.Fab")
		)
		(fp_line
			(start -0.12065 0.2794)
			(end -0.12065 0.3048)
			(stroke
				(width 0.1)
				(type default)
			)
			(layer "F.Fab")
		)
		(fp_line
			(start -0.12065 0.3048)
			(end -0.67945 0.3048)
			(stroke
				(width 0.1)
				(type default)
			)
			(layer "F.Fab")
		)
		(fp_line
			(start 0.120396 0.2794)
			(end -0.12065 0.2794)
			(stroke
				(width 0.1)
				(type default)
			)
			(layer "F.Fab")
		)
		(fp_line
			(start 0.120396 0.3048)
			(end 0.120396 0.2794)
			(stroke
				(width 0.1)
				(type default)
			)
			(layer "F.Fab")
		)
		(fp_line
			(start 0.12065 -0.3048)
			(end 0.67945 -0.3048)
			(stroke
				(width 0.1)
				(type default)
			)
			(layer "F.Fab")
		)
		(fp_line
			(start 0.12065 -0.2794)
			(end 0.12065 -0.3048)
			(stroke
				(width 0.1)
				(type default)
			)
			(layer "F.Fab")
		)
		(fp_line
			(start 0.67945 -0.3048)
			(end 0.67945 0.3048)
			(stroke
				(width 0.1)
				(type default)
			)
			(layer "F.Fab")
		)
		(fp_line
			(start 0.67945 0.3048)
			(end 0.120396 0.3048)
			(stroke
				(width 0.1)
				(type default)
			)
			(layer "F.Fab")
		)
		(pad "1" smd circle
			(at -0.40005 0)
			(size 0 0)
			(layers "F.Cu" "F.Mask" "F.Paste")
			(net "P3V3_AUX")
		)
		(pad "2" smd circle
			(at 0.40005 0)
			(size 0 0)
			(layers "F.Cu" "F.Mask" "F.Paste")
			(net "PWRGD_P3V3_SSD14_D")
		)
	)
	(footprint ""
		(layer "F.Cu")
		(at 217.235786 -216.270586 180)
		(property "Reference" "R1502"
			(at 0 0 180)
			(layer "F.SilkS")
			(hide yes)
			(effects
				(font
					(size 1.27 1.27)
				)
			)
		)
		(property "Value" ""
			(at 0 0 180)
			(layer "F.Fab")
			(effects
				(font
					(size 1.27 1.27)
				)
			)
		)
		(duplicate_pad_numbers_are_jumpers no)
		(fp_line
			(start 0.7874 0.4064)
			(end -0.7874 0.4064)
			(stroke
				(width 0.1524)
				(type default)
			)
			(layer "F.SilkS")
		)
		(fp_line
			(start 0.7874 -0.4064)
			(end 0.7874 0.4064)
			(stroke
				(width 0.1524)
				(type default)
			)
			(layer "F.SilkS")
		)
		(fp_line
			(start -0.7874 0.4064)
			(end -0.7874 -0.4064)
			(stroke
				(width 0.1524)
				(type default)
			)
			(layer "F.SilkS")
		)
		(fp_line
			(start -0.7874 -0.4064)
			(end 0.7874 -0.4064)
			(stroke
				(width 0.1524)
				(type default)
			)
			(layer "F.SilkS")
		)
		(fp_line
			(start 0.67945 0.3048)
			(end 0.120396 0.3048)
			(stroke
				(width 0.1)
				(type default)
			)
			(layer "F.Fab")
		)
		(fp_line
			(start 0.67945 -0.3048)
			(end 0.67945 0.3048)
			(stroke
				(width 0.1)
				(type default)
			)
			(layer "F.Fab")
		)
		(fp_line
			(start 0.12065 -0.2794)
			(end 0.12065 -0.3048)
			(stroke
				(width 0.1)
				(type default)
			)
			(layer "F.Fab")
		)
		(fp_line
			(start 0.12065 -0.3048)
			(end 0.67945 -0.3048)
			(stroke
				(width 0.1)
				(type default)
			)
			(layer "F.Fab")
		)
		(fp_line
			(start 0.120396 0.3048)
			(end 0.120396 0.2794)
			(stroke
				(width 0.1)
				(type default)
			)
			(layer "F.Fab")
		)
		(fp_line
			(start 0.120396 0.2794)
			(end -0.12065 0.2794)
			(stroke
				(width 0.1)
				(type default)
			)
			(layer "F.Fab")
		)
		(fp_line
			(start -0.12065 0.3048)
			(end -0.67945 0.3048)
			(stroke
				(width 0.1)
				(type default)
			)
			(layer "F.Fab")
		)
		(fp_line
			(start -0.12065 0.2794)
			(end -0.12065 0.3048)
			(stroke
				(width 0.1)
				(type default)
			)
			(layer "F.Fab")
		)
		(fp_line
			(start -0.12065 -0.2794)
			(end 0.12065 -0.2794)
			(stroke
				(width 0.1)
				(type default)
			)
			(layer "F.Fab")
		)
		(fp_line
			(start -0.12065 -0.305054)
			(end -0.12065 -0.2794)
			(stroke
				(width 0.1)
				(type default)
			)
			(layer "F.Fab")
		)
		(fp_line
			(start -0.67945 0.3048)
			(end -0.67945 -0.305054)
			(stroke
				(width 0.1)
				(type default)
			)
			(layer "F.Fab")
		)
		(fp_line
			(start -0.67945 -0.305054)
			(end -0.12065 -0.305054)
			(stroke
				(width 0.1)
				(type default)
			)
			(layer "F.Fab")
		)
		(pad "1" smd circle
			(at -0.40005 0 180)
			(size 0 0)
			(layers "F.Cu" "F.Mask" "F.Paste")
			(net "SMB_NIC6_SCL")
		)
		(pad "2" smd circle
			(at 0.40005 0 180)
			(size 0 0)
			(layers "F.Cu" "F.Mask" "F.Paste")
			(net "SMB_NIC6_R_SCL")
		)
	)
	(footprint ""
		(layer "F.Cu")
		(at 363.104684 -384.01498 -90)
		(property "Reference" "Q247"
			(at -0.223012 -3.465068 0)
			(unlocked yes)
			(layer "F.SilkS")
			(effects
				(font
					(size 0.7874 0.5842)
					(thickness 0.1524)
				)
			)
		)
		(property "Value" ""
			(at 0 0 270)
			(layer "F.Fab")
			(effects
				(font
					(size 1.27 1.27)
				)
			)
		)
		(duplicate_pad_numbers_are_jumpers no)
		(fp_line
			(start -1.376172 1.199896)
			(end -1.376172 -1.199896)
			(stroke
				(width 0.1524)
				(type default)
			)
			(layer "F.SilkS")
		)
		(fp_line
			(start 1.376172 1.199896)
			(end -1.376172 1.199896)
			(stroke
				(width 0.1524)
				(type default)
			)
			(layer "F.SilkS")
		)
		(fp_line
			(start 0 -0.762)
			(end 0.508 -1.199896)
			(stroke
				(width 0.1524)
				(type default)
			)
			(layer "F.SilkS")
		)
		(fp_line
			(start -1.376172 -1.199896)
			(end -0.508 -1.199896)
			(stroke
				(width 0.1524)
				(type default)
			)
			(layer "F.SilkS")
		)
		(fp_line
			(start -0.508 -1.199896)
			(end 0 -0.762)
			(stroke
				(width 0.1524)
				(type default)
			)
			(layer "F.SilkS")
		)
		(fp_line
			(start 0.508 -1.199896)
			(end 1.376172 -1.199896)
			(stroke
				(width 0.1524)
				(type default)
			)
			(layer "F.SilkS")
		)
		(fp_line
			(start 1.376172 -1.199896)
			(end 1.376172 1.199896)
			(stroke
				(width 0.1524)
				(type default)
			)
			(layer "F.SilkS")
		)
		(fp_poly
			(pts
				(xy -1.4605 -0.7493) (xy -2.2225 -1.1303) (xy -2.2225 -0.3683)
			)
			(stroke
				(width 0)
				(type default)
			)
			(fill yes)
			(layer "F.SilkS")
		)
		(fp_line
			(start -0.674878 1.100074)
			(end -0.674878 -1.100074)
			(stroke
				(width 0.1)
				(type default)
			)
			(layer "F.Fab")
		)
		(fp_line
			(start 0.674878 1.100074)
			(end -0.674878 1.100074)
			(stroke
				(width 0.1)
				(type default)
			)
			(layer "F.Fab")
		)
		(fp_line
			(start -0.674878 -1.100074)
			(end 0.674878 -1.100074)
			(stroke
				(width 0.1)
				(type default)
			)
			(layer "F.Fab")
		)
		(fp_line
			(start 0.674878 -1.100074)
			(end 0.674878 1.100074)
			(stroke
				(width 0.1)
				(type default)
			)
			(layer "F.Fab")
		)
		(fp_poly
			(pts
				(xy -1.4605 -0.7493) (xy -2.2225 -1.1303) (xy -2.2225 -0.3683)
			)
			(stroke
				(width 0)
				(type default)
			)
			(fill yes)
			(layer "F.Fab")
		)
		(pad "1" smd rect
			(at -0.899922 -0.750062 180)
			(size 0.6096 0.6096)
			(layers "F.Cu" "F.Mask" "F.Paste")
			(net "GND")
		)
		(pad "2" smd rect
			(at -0.899922 0 180)
			(size 0.4064 0.6096)
			(layers "F.Cu" "F.Mask" "F.Paste")
			(net "MB_3V3IO_RSVD4")
		)
		(pad "3" smd rect
			(at -0.899922 0.750062 180)
			(size 0.6096 0.6096)
			(layers "F.Cu" "F.Mask" "F.Paste")
			(net "MB_3V3IO_RSVD4_ISO")
		)
		(pad "4" smd rect
			(at 0.899922 0.750062 180)
			(size 0.6096 0.6096)
			(layers "F.Cu" "F.Mask" "F.Paste")
			(net "GND")
		)
		(pad "5" smd rect
			(at 0.899922 0 180)
			(size 0.4064 0.6096)
			(layers "F.Cu" "F.Mask" "F.Paste")
			(net "MB_3V3IO_RSVD4_N")
		)
		(pad "6" smd rect
			(at 0.899922 -0.750062 180)
			(size 0.6096 0.6096)
			(layers "F.Cu" "F.Mask" "F.Paste")
			(net "MB_3V3IO_RSVD4_N")
		)
	)
	(footprint ""
		(layer "F.Cu")
		(at 334.899 -244.729 90)
		(property "Reference" "C2746"
			(at 0 0 90)
			(layer "F.SilkS")
			(hide yes)
			(effects
				(font
					(size 1.27 1.27)
				)
			)
		)
		(property "Value" ""
			(at 0 0 90)
			(layer "F.Fab")
			(effects
				(font
					(size 1.27 1.27)
				)
			)
		)
		(duplicate_pad_numbers_are_jumpers no)
		(fp_line
			(start 0.7874 -0.4064)
			(end 0.7874 0.4064)
			(stroke
				(width 0.1524)
				(type default)
			)
			(layer "F.SilkS")
		)
		(fp_line
			(start -0.7874 -0.4064)
			(end 0.7874 -0.4064)
			(stroke
				(width 0.1524)
				(type default)
			)
			(layer "F.SilkS")
		)
		(fp_line
			(start 0.7874 0.4064)
			(end -0.7874 0.4064)
			(stroke
				(width 0.1524)
				(type default)
			)
			(layer "F.SilkS")
		)
		(fp_line
			(start -0.7874 0.4064)
			(end -0.7874 -0.4064)
			(stroke
				(width 0.1524)
				(type default)
			)
			(layer "F.SilkS")
		)
		(fp_line
			(start -0.12065 -0.305054)
			(end -0.12065 -0.2794)
			(stroke
				(width 0.1)
				(type default)
			)
			(layer "F.Fab")
		)
		(fp_line
			(start -0.67945 -0.305054)
			(end -0.12065 -0.305054)
			(stroke
				(width 0.1)
				(type default)
			)
			(layer "F.Fab")
		)
		(fp_line
			(start 0.67945 -0.3048)
			(end 0.67945 0.3048)
			(stroke
				(width 0.1)
				(type default)
			)
			(layer "F.Fab")
		)
		(fp_line
			(start 0.12065 -0.3048)
			(end 0.67945 -0.3048)
			(stroke
				(width 0.1)
				(type default)
			)
			(layer "F.Fab")
		)
		(fp_line
			(start 0.12065 -0.2794)
			(end 0.12065 -0.3048)
			(stroke
				(width 0.1)
				(type default)
			)
			(layer "F.Fab")
		)
		(fp_line
			(start -0.12065 -0.2794)
			(end 0.12065 -0.2794)
			(stroke
				(width 0.1)
				(type default)
			)
			(layer "F.Fab")
		)
		(fp_line
			(start 0.120396 0.2794)
			(end -0.12065 0.2794)
			(stroke
				(width 0.1)
				(type default)
			)
			(layer "F.Fab")
		)
		(fp_line
			(start -0.12065 0.2794)
			(end -0.12065 0.3048)
			(stroke
				(width 0.1)
				(type default)
			)
			(layer "F.Fab")
		)
		(fp_line
			(start 0.67945 0.3048)
			(end 0.120396 0.3048)
			(stroke
				(width 0.1)
				(type default)
			)
			(layer "F.Fab")
		)
		(fp_line
			(start 0.120396 0.3048)
			(end 0.120396 0.2794)
			(stroke
				(width 0.1)
				(type default)
			)
			(layer "F.Fab")
		)
		(fp_line
			(start -0.12065 0.3048)
			(end -0.67945 0.3048)
			(stroke
				(width 0.1)
				(type default)
			)
			(layer "F.Fab")
		)
		(fp_line
			(start -0.67945 0.3048)
			(end -0.67945 -0.305054)
			(stroke
				(width 0.1)
				(type default)
			)
			(layer "F.Fab")
		)
		(pad "1" smd circle
			(at -0.40005 0 90)
			(size 0 0)
			(layers "F.Cu" "F.Mask" "F.Paste")
			(net "P3V3_AUX")
		)
		(pad "2" smd circle
			(at 0.40005 0 90)
			(size 0 0)
			(layers "F.Cu" "F.Mask" "F.Paste")
			(net "GND")
		)
	)
)
